# S9S_MB_2U (Grand Teton) — schematic netlist excerpt (pin names and nets, part order shuffled) for the footprints in the layout excerpt that follows; sources: Cadence DE-HDL packaged netlist, KiCad conversion of 03242023_DA0F0TMBIJ0_F0T_Motherboard_J_brd_V01_OCP.brd

R1384  Q_RES  2K 1% EMPTY  pkg 0402LF  page 241 : A = SMB_SML0_3V3AUX_SCL ; B = P3V3_AUX
R4117  Q_RES  10K 1% CHIP  pkg 0402LF  page 184 : A = PD_PCH_GPP_E_3 ; B = GND

(kicad_pcb
	(version 20260206)
	(generator "pcbnew")
	(generator_version "10.0")
	(general
		(thickness 1.6)
		(legacy_teardrops no)
	)
	(paper "A4")
	(title_block
		(title "03242023_DA0F0TMBIJ0_F0T_Motherboard_J_brd_V01_OCP.brd")
		(comment 1 "Grand Teton / footprints 4501-4502 of 6105")
	)
	(layers
		(0 "F.Cu" signal "TOP")
		(4 "In1.Cu" signal "GND")
		(6 "In2.Cu" signal "IN1")
		(8 "In3.Cu" signal "GND1")
		(10 "In4.Cu" signal "IN2")
		(12 "In5.Cu" signal "GND2")
		(14 "In6.Cu" signal "IN3")
		(16 "In7.Cu" signal "GND3")
		(18 "In8.Cu" signal "VCC")
		(20 "In9.Cu" signal "VCC1")
		(22 "In10.Cu" signal "GND4")
		(24 "In11.Cu" signal "IN4")
		(26 "In12.Cu" signal "GND5")
		(28 "In13.Cu" signal "IN5")
		(30 "In14.Cu" signal "GND6")
		(32 "In15.Cu" signal "IN6")
		(34 "In16.Cu" signal "GND7")
		(2 "B.Cu" signal "BOTTOM")
		(9 "F.Adhes" user "F.Adhesive")
		(11 "B.Adhes" user "B.Adhesive")
		(13 "F.Paste" user "Package Geometry/Pastemask Top")
		(15 "B.Paste" user "Package Geometry/Pastemask Bottom")
		(5 "F.SilkS" user "Ref Des/Silkscreen Top")
		(7 "B.SilkS" user "Ref Des/Silkscreen Bottom")
		(1 "F.Mask" user "Board Geometry/Soldermask Top")
		(3 "B.Mask" user "Board Geometry/Soldermask Bottom")
		(17 "Dwgs.User" user "User.Drawings")
		(19 "Cmts.User" user "User.Comments")
		(21 "Eco1.User" user "User.Eco1")
		(23 "Eco2.User" user "User.Eco2")
		(25 "Edge.Cuts" user "Board Geometry/Outline")
		(27 "Margin" user)
		(31 "F.CrtYd" user "Package Geometry/Place Bound Top")
		(29 "B.CrtYd" user "Package Geometry/Place Bound Bottom")
		(35 "F.Fab" user "Ref Des/Assembly Top")
		(33 "B.Fab" user "Ref Des/Assembly Bottom")
	)
	(footprint ""
		(layer "B.Cu")
		(at 162.306 -15.712948 -90)
		(property "Reference" "R1384"
			(at 0 0 90)
			(layer "B.SilkS")
			(hide yes)
			(effects
				(font
					(size 1.27 1.27)
				)
				(justify mirror)
			)
		)
		(property "Value" ""
			(at 0 0 90)
			(layer "B.Fab")
			(effects
				(font
					(size 1.27 1.27)
				)
				(justify mirror)
			)
		)
		(duplicate_pad_numbers_are_jumpers no)
		(fp_line
			(start -0.7874 0.4064)
			(end 0.7874 0.4064)
			(stroke
				(width 0.1524)
				(type default)
			)
			(layer "B.SilkS")
		)
		(fp_line
			(start 0.7874 0.4064)
			(end 0.7874 -0.4064)
			(stroke
				(width 0.1524)
				(type default)
			)
			(layer "B.SilkS")
		)
		(fp_line
			(start -0.7874 -0.4064)
			(end -0.7874 0.4064)
			(stroke
				(width 0.1524)
				(type default)
			)
			(layer "B.SilkS")
		)
		(fp_line
			(start 0.7874 -0.4064)
			(end -0.7874 -0.4064)
			(stroke
				(width 0.1524)
				(type default)
			)
			(layer "B.SilkS")
		)
		(fp_line
			(start -0.67945 0.3048)
			(end -0.120396 0.3048)
			(stroke
				(width 0.1)
				(type default)
			)
			(layer "B.Fab")
		)
		(fp_line
			(start -0.120396 0.3048)
			(end -0.120396 0.2794)
			(stroke
				(width 0.1)
				(type default)
			)
			(layer "B.Fab")
		)
		(fp_line
			(start 0.12065 0.3048)
			(end 0.67945 0.3048)
			(stroke
				(width 0.1)
				(type default)
			)
			(layer "B.Fab")
		)
		(fp_line
			(start 0.67945 0.3048)
			(end 0.67945 -0.305054)
			(stroke
				(width 0.1)
				(type default)
			)
			(layer "B.Fab")
		)
		(fp_line
			(start -0.120396 0.2794)
			(end 0.12065 0.2794)
			(stroke
				(width 0.1)
				(type default)
			)
			(layer "B.Fab")
		)
		(fp_line
			(start 0.12065 0.2794)
			(end 0.12065 0.3048)
			(stroke
				(width 0.1)
				(type default)
			)
			(layer "B.Fab")
		)
		(fp_line
			(start -0.12065 -0.2794)
			(end -0.12065 -0.3048)
			(stroke
				(width 0.1)
				(type default)
			)
			(layer "B.Fab")
		)
		(fp_line
			(start 0.12065 -0.2794)
			(end -0.12065 -0.2794)
			(stroke
				(width 0.1)
				(type default)
			)
			(layer "B.Fab")
		)
		(fp_line
			(start -0.67945 -0.3048)
			(end -0.67945 0.3048)
			(stroke
				(width 0.1)
				(type default)
			)
			(layer "B.Fab")
		)
		(fp_line
			(start -0.12065 -0.3048)
			(end -0.67945 -0.3048)
			(stroke
				(width 0.1)
				(type default)
			)
			(layer "B.Fab")
		)
		(fp_line
			(start 0.12065 -0.305054)
			(end 0.12065 -0.2794)
			(stroke
				(width 0.1)
				(type default)
			)
			(layer "B.Fab")
		)
		(fp_line
			(start 0.67945 -0.305054)
			(end 0.12065 -0.305054)
			(stroke
				(width 0.1)
				(type default)
			)
			(layer "B.Fab")
		)
		(pad "1" smd circle
			(at 0.40005 0 90)
			(size 0 0)
			(layers "B.Cu" "B.Mask" "B.Paste")
			(net "SMB_SML0_3V3AUX_SCL")
		)
		(pad "2" smd circle
			(at -0.40005 0 90)
			(size 0 0)
			(layers "B.Cu" "B.Mask" "B.Paste")
			(net "P3V3_AUX")
		)
	)
	(footprint ""
		(layer "B.Cu")
		(at 369.49888 -37.937948 180)
		(property "Reference" "R4117"
			(at 0 0 0)
			(layer "B.SilkS")
			(hide yes)
			(effects
				(font
					(size 1.27 1.27)
				)
				(justify mirror)
			)
		)
		(property "Value" ""
			(at 0 0 0)
			(layer "B.Fab")
			(effects
				(font
					(size 1.27 1.27)
				)
				(justify mirror)
			)
		)
		(duplicate_pad_numbers_are_jumpers no)
		(fp_line
			(start 0.7874 0.4064)
			(end 0.7874 -0.4064)
			(stroke
				(width 0.1524)
				(type default)
			)
			(layer "B.SilkS")
		)
		(fp_line
			(start 0.7874 -0.4064)
			(end -0.7874 -0.4064)
			(stroke
				(width 0.1524)
				(type default)
			)
			(layer "B.SilkS")
		)
		(fp_line
			(start -0.7874 0.4064)
			(end 0.7874 0.4064)
			(stroke
				(width 0.1524)
				(type default)
			)
			(layer "B.SilkS")
		)
		(fp_line
			(start -0.7874 -0.4064)
			(end -0.7874 0.4064)
			(stroke
				(width 0.1524)
				(type default)
			)
			(layer "B.SilkS")
		)
		(fp_line
			(start 0.67945 0.3048)
			(end 0.67945 -0.305054)
			(stroke
				(width 0.1)
				(type default)
			)
			(layer "B.Fab")
		)
		(fp_line
			(start 0.67945 -0.305054)
			(end 0.12065 -0.305054)
			(stroke
				(width 0.1)
				(type default)
			)
			(layer "B.Fab")
		)
		(fp_line
			(start 0.12065 0.3048)
			(end 0.67945 0.3048)
			(stroke
				(width 0.1)
				(type default)
			)
			(layer "B.Fab")
		)
		(fp_line
			(start 0.12065 0.2794)
			(end 0.12065 0.3048)
			(stroke
				(width 0.1)
				(type default)
			)
			(layer "B.Fab")
		)
		(fp_line
			(start 0.12065 -0.2794)
			(end -0.12065 -0.2794)
			(stroke
				(width 0.1)
				(type default)
			)
			(layer "B.Fab")
		)
		(fp_line
			(start 0.12065 -0.305054)
			(end 0.12065 -0.2794)
			(stroke
				(width 0.1)
				(type default)
			)
			(layer "B.Fab")
		)
		(fp_line
			(start -0.120396 0.3048)
			(end -0.120396 0.2794)
			(stroke
				(width 0.1)
				(type default)
			)
			(layer "B.Fab")
		)
		(fp_line
			(start -0.120396 0.2794)
			(end 0.12065 0.2794)
			(stroke
				(width 0.1)
				(type default)
			)
			(layer "B.Fab")
		)
		(fp_line
			(start -0.12065 -0.2794)
			(end -0.12065 -0.3048)
			(stroke
				(width 0.1)
				(type default)
			)
			(layer "B.Fab")
		)
		(fp_line
			(start -0.12065 -0.3048)
			(end -0.67945 -0.3048)
			(stroke
				(width 0.1)
				(type default)
			)
			(layer "B.Fab")
		)
		(fp_line
			(start -0.67945 0.3048)
			(end -0.120396 0.3048)
			(stroke
				(width 0.1)
				(type default)
			)
			(layer "B.Fab")
		)
		(fp_line
			(start -0.67945 -0.3048)
			(end -0.67945 0.3048)
			(stroke
				(width 0.1)
				(type default)
			)
			(layer "B.Fab")
		)
		(pad "1" smd circle
			(at 0.40005 0)
			(size 0 0)
			(layers "B.Cu" "B.Mask" "B.Paste")
			(net "PD_PCH_GPP_E_3")
		)
		(pad "2" smd circle
			(at -0.40005 0)
			(size 0 0)
			(layers "B.Cu" "B.Mask" "B.Paste")
			(net "GND")
		)
	)
)
